G04 ================== begin FILE IDENTIFICATION RECORD ==================*
G04 Layout Name:  13130-1b.brd*
G04 Film Name:    DIF_REF_BOTTOM*
G04 File Format:  Gerber RS274X*
G04 File Origin:  Cadence Allegro 16.5-S037*
G04 Origin Date:  Thu Nov 13 18:47:02 2014*
G04 *
G04 Layer:  BOARD GEOMETRY/OUTLINE*
G04 Layer:  BOARD GEOMETRY/DIF_REF_BOTTOM*
G04 Layer:  BOARD GEOMETRY/PANEL_OUTLINE*
G04 *
G04 Offset:    (0.00 0.00)*
G04 Mirror:    No*
G04 Mode:      Positive*
G04 Rotation:  0*
G04 FullContactRelief:  No*
G04 UndefLineWidth:     6.00*
G04 ================== end FILE IDENTIFICATION RECORD ====================*
%FSLAX35Y35*MOIN*%
%IR0*IPPOS*OFA0.00000B0.00000*MIA0B0*SFA1.00000B1.00000*%
%ADD10C,.004*%
%ADD11C,.005*%
%ADD12C,.006*%
%ADD13C,.007*%
%ADD14C,.0055*%
%ADD15C,.0085*%
G75*
%LPD*%
G75*
G54D10*
G01X302725Y116000D02*
Y115900D01*
G01X303000Y116275D02*
X302725Y116000D01*
G01X303000Y121932D02*
Y116275D01*
G01X304075Y116000D02*
Y115900D01*
G01X303800Y116275D02*
X304075Y116000D01*
G01X303800Y118420D02*
Y116275D01*
G01X304190Y118810D02*
X303800Y118420D01*
G01X304190Y120010D02*
Y118810D01*
G01X303800Y120400D02*
X304190Y120010D01*
G01X303800Y121600D02*
Y120400D01*
G01X306668Y125600D02*
X303000Y121932D01*
G01X312400Y125600D02*
X306668D01*
G01X307000Y124800D02*
X303800Y121600D01*
G01X312732Y124800D02*
X307000D01*
G01X313600Y126800D02*
X312400Y125600D01*
G01X316263Y126800D02*
X313600D01*
G01X317831Y125232D02*
X316263Y126800D01*
G01X317831Y123770D02*
Y125232D01*
G01X318376Y123225D02*
X317831Y123770D01*
G01X319418Y123225D02*
X318376D01*
G01X313932Y126000D02*
X312732Y124800D01*
G01X315931Y126000D02*
X313932D01*
G01X317031Y124900D02*
X315931Y126000D01*
G01X317031Y123698D02*
Y124900D01*
G01X316552Y123219D02*
X317031Y123698D01*
G01X315451Y123219D02*
X316552D01*
G54D11*
G01X87500Y206000D02*
X89500Y204000D01*
G01X86000Y206000D02*
X87500D01*
G01X92900Y207400D02*
X93500Y208000D01*
G01X92900Y204008D02*
Y207400D01*
G54D12*
G01X-31497Y-1D02*
X26377D01*
G01X-35434Y3936D02*
G03X-31497Y-1I3937J0D01*
G01X-35434Y585039D02*
Y3936D01*
G01X-7874Y588976D02*
X-31497D01*
G01D02*
G03X-35434Y585039I0J-3937D01*
G01X-12698Y15747D02*
G03I-6988J0D01*
G01Y573227D02*
G03I-6988J0D01*
G01X822835Y290551D02*
X3937D01*
G03X0Y286614I0J-3937D01*
G01Y61811D01*
G03X3937Y57874I3937J0D01*
G01X53937D01*
G02X57874Y53937I0J-3937D01*
G01Y16142D01*
X338189D01*
Y39961D01*
G02X345669I3740J0D01*
G01Y16142D01*
X389764D01*
Y42126D01*
G02X393701Y46063I3937J0D01*
G01X409449D01*
G02X413386Y42126I0J-3937D01*
G01Y3937D01*
G03X417323Y0I3937J0D01*
G01X822835D01*
G03X826772Y3937I0J3937D01*
G01Y286614D01*
G03X822835Y290551I-3937J0D01*
G01X826773Y286614D02*
G03X822836Y290551I-3937J0D01*
G01X3938D01*
G03X1Y286614I0J-3937D01*
G01Y61811D01*
G03X3938Y57874I3937J0D01*
G01X53938D01*
G02X57875Y53937I0J-3937D01*
G01Y12598D01*
X59844Y10629D01*
X336222D01*
X338190Y12598D01*
Y39960D01*
G02X345671I3740J0D01*
G01Y12598D01*
X347639Y10629D01*
X387797D01*
X389765Y12598D01*
Y42126D01*
G02X393702Y46063I3937J0D01*
G01X409450D01*
G02X413387Y42126I0J-3937D01*
G01Y3937D01*
G03X417324Y0I3937J0D01*
G01X822836D01*
G03X826773Y3937I0J3937D01*
G01Y286614D01*
G01D02*
G03X822836Y290551I-3937J0D01*
G01X3938D01*
G03X1Y286614I0J-3937D01*
G01Y61811D01*
G03X3938Y57874I3937J0D01*
G01X53938D01*
G02X57875Y53937I0J-3937D01*
G01Y12598D01*
X59844Y10629D01*
X336222D01*
X338190Y12598D01*
Y39960D01*
G02X345671I3740J0D01*
G01Y12598D01*
X347639Y10629D01*
X387797D01*
X389765Y12598D01*
Y42126D01*
G02X393702Y46063I3937J0D01*
G01X409450D01*
G02X413387Y42126I0J-3937D01*
G01Y3937D01*
G03X417324Y0I3937J0D01*
G01X822836D01*
G03X826773Y3937I0J3937D01*
G01Y286614D01*
G01X22440Y49999D02*
X-3937D01*
G01X-7874Y53936D02*
Y72440D01*
G01Y53936D02*
G03X-3937Y49999I3937J0D01*
G01X0Y72440D02*
G03X-7874I-3937J0D01*
G01Y103149D02*
G03X0I3937J0D01*
G01X-7874D02*
Y210235D01*
G01X0D02*
G03X-7874I-3937J0D01*
G01Y240944D02*
Y348031D01*
G01Y240944D02*
G03X0I3937J0D01*
G01X-3Y302361D02*
G03X3934Y298424I3937J0D01*
G01X822832D01*
G03X826769Y302361I0J3937D01*
G01Y527164D01*
G03X822832Y531101I-3937J0D01*
G01X772832D01*
G02X768895Y535038I0J3937D01*
G01Y576377D01*
X766926Y578346D01*
X490548D01*
X488580Y576377D01*
Y549015D01*
G02X481099I-3740J0D01*
G01Y576377D01*
X479131Y578346D01*
X438973D01*
X437005Y576377D01*
Y546849D01*
G02X433068Y542912I-3937J0D01*
G01X417320D01*
G02X413383Y546849I0J3937D01*
G01Y585038D01*
G03X409446Y588975I-3937J0D01*
G01X3934D01*
G03X-3Y585038I0J-3937D01*
G01Y302361D01*
G01X0Y348031D02*
G03X-7874I-3937J0D01*
G01Y378739D02*
Y485826D01*
G01Y378739D02*
G03X0I3937J0D01*
G01Y485826D02*
G03X-7874I-3937J0D01*
G01Y516535D02*
Y588976D01*
G01Y516535D02*
G03X0I3937J-1D01*
G01X17137Y687650D02*
Y675650D01*
G01X14837Y687650D02*
X19437D01*
G01X21437Y675650D02*
Y687650D01*
G01Y681850D02*
X21937Y682850D01*
X22437Y683450D01*
X23237Y683650D01*
X23837Y683450D01*
X24537Y682650D01*
X24837Y681450D01*
Y675650D01*
G01X29137Y683650D02*
Y675650D01*
G01Y686850D02*
X28937Y687050D01*
Y687450D01*
X29137Y687650D01*
X29337Y687450D01*
Y687050D01*
X29137Y686850D01*
G01X33637Y677050D02*
X34137Y676250D01*
X34837Y675650D01*
X35437D01*
X36037Y676050D01*
X36437Y676650D01*
X36637Y677450D01*
X36537Y678650D01*
X36137Y679250D01*
X34337Y680450D01*
X33937Y681850D01*
X34137Y682850D01*
X34537Y683450D01*
X35137Y683650D01*
X35737Y683450D01*
X36337Y682850D01*
G01X45737Y672650D02*
X46437Y671850D01*
X47237Y671650D01*
X47937Y671850D01*
X48537Y672850D01*
X48937Y674250D01*
Y683650D01*
G01Y682050D02*
X48537Y682850D01*
X47937Y683450D01*
X47237Y683650D01*
X46437Y683250D01*
X45937Y682450D01*
X45537Y681050D01*
X45337Y679650D01*
X45437Y678450D01*
X45837Y677050D01*
X46437Y676050D01*
X47237Y675650D01*
X47837Y675850D01*
X48537Y676650D01*
X48937Y677450D01*
G01X51637Y681050D02*
X54837D01*
X54537Y682450D01*
X54037Y683250D01*
X53337Y683650D01*
X52637Y683450D01*
X52037Y682850D01*
X51637Y681450D01*
X51437Y680250D01*
Y679050D01*
X51637Y677850D01*
X52137Y676650D01*
X52737Y675850D01*
X53437Y675650D01*
X54137Y676050D01*
X54837Y677250D01*
G01X57737Y675650D02*
Y683650D01*
G01Y682050D02*
X58237Y682850D01*
X58737Y683450D01*
X59437Y683650D01*
X59937Y683450D01*
X60537Y682850D01*
G01X63337Y675650D02*
Y687650D01*
G01Y681650D02*
X63837Y682850D01*
X64437Y683450D01*
X65037Y683650D01*
X65937Y683250D01*
X66537Y682450D01*
X66937Y681050D01*
Y679450D01*
X66737Y677850D01*
X66337Y676650D01*
X65637Y675850D01*
X65037Y675650D01*
X64437Y675850D01*
X63837Y676450D01*
X63337Y677450D01*
G01X69637Y681050D02*
X72837D01*
X72537Y682450D01*
X72037Y683250D01*
X71337Y683650D01*
X70637Y683450D01*
X70037Y682850D01*
X69637Y681450D01*
X69437Y680250D01*
Y679050D01*
X69637Y677850D01*
X70137Y676650D01*
X70737Y675850D01*
X71437Y675650D01*
X72137Y676050D01*
X72837Y677250D01*
G01X75737Y675650D02*
Y683650D01*
G01Y682050D02*
X76237Y682850D01*
X76737Y683450D01*
X77437Y683650D01*
X77937Y683450D01*
X78537Y682850D01*
G01X89137Y683650D02*
Y675650D01*
G01Y686850D02*
X88937Y687050D01*
Y687450D01*
X89137Y687650D01*
X89337Y687450D01*
Y687050D01*
X89137Y686850D01*
G01X93637Y677050D02*
X94137Y676250D01*
X94837Y675650D01*
X95437D01*
X96037Y676050D01*
X96437Y676650D01*
X96637Y677450D01*
X96537Y678650D01*
X96137Y679250D01*
X94337Y680450D01*
X93937Y681850D01*
X94137Y682850D01*
X94537Y683450D01*
X95137Y683650D01*
X95737Y683450D01*
X96337Y682850D01*
G01X105537Y672650D02*
X106237Y671850D01*
X106837Y671650D01*
X107637Y672050D01*
X108237Y673050D01*
X108537Y674850D01*
Y683650D01*
G01Y686850D02*
X108337Y687050D01*
Y687450D01*
X108537Y687650D01*
X108737Y687450D01*
Y687050D01*
X108537Y686850D01*
G01X111437Y683650D02*
Y678050D01*
X111837Y676650D01*
X112437Y675850D01*
X113137Y675650D01*
X113837Y675850D01*
X114437Y676650D01*
X114837Y678050D01*
G01Y675650D02*
Y683650D01*
G01X117637Y677050D02*
X118137Y676250D01*
X118837Y675650D01*
X119437D01*
X120037Y676050D01*
X120437Y676650D01*
X120637Y677450D01*
X120537Y678650D01*
X120137Y679250D01*
X118337Y680450D01*
X117937Y681850D01*
X118137Y682850D01*
X118537Y683450D01*
X119137Y683650D01*
X119737Y683450D01*
X120337Y682850D01*
G01X125137Y687650D02*
Y675650D01*
G01X123737Y683650D02*
X126537D01*
G01X136537Y675650D02*
Y685850D01*
X136737Y686850D01*
X137137Y687450D01*
X137737Y687650D01*
X138337Y687250D01*
X138637Y686250D01*
G01X137437Y682850D02*
X135437D01*
G01X143137Y675650D02*
X142537Y675850D01*
X141937Y676650D01*
X141537Y678050D01*
X141337Y679650D01*
X141537Y681250D01*
X141937Y682650D01*
X142537Y683450D01*
X143137Y683650D01*
X143737Y683450D01*
X144337Y682650D01*
X144737Y681250D01*
X144837Y679650D01*
X144737Y678050D01*
X144337Y676650D01*
X143737Y675850D01*
X143137Y675650D01*
G01X147737D02*
Y683650D01*
G01Y682050D02*
X148237Y682850D01*
X148737Y683450D01*
X149437Y683650D01*
X149937Y683450D01*
X150537Y682850D01*
G01X159037Y672050D02*
X159637Y671650D01*
X160437Y672050D01*
X160937Y672850D01*
X161337Y673850D01*
X161937Y677050D01*
X163237Y683650D01*
G01X160037D02*
X161937Y677050D01*
G01X167137Y675650D02*
X166537Y675850D01*
X165937Y676650D01*
X165537Y678050D01*
X165337Y679650D01*
X165537Y681250D01*
X165937Y682650D01*
X166537Y683450D01*
X167137Y683650D01*
X167737Y683450D01*
X168337Y682650D01*
X168737Y681250D01*
X168837Y679650D01*
X168737Y678050D01*
X168337Y676650D01*
X167737Y675850D01*
X167137Y675650D01*
G01X171437Y683650D02*
Y678050D01*
X171837Y676650D01*
X172437Y675850D01*
X173137Y675650D01*
X173837Y675850D01*
X174437Y676650D01*
X174837Y678050D01*
G01Y675650D02*
Y683650D01*
G01X183737Y675650D02*
Y683650D01*
G01Y682050D02*
X184237Y682850D01*
X184737Y683450D01*
X185437Y683650D01*
X185937Y683450D01*
X186537Y682850D01*
G01X189637Y681050D02*
X192837D01*
X192537Y682450D01*
X192037Y683250D01*
X191337Y683650D01*
X190637Y683450D01*
X190037Y682850D01*
X189637Y681450D01*
X189437Y680250D01*
Y679050D01*
X189637Y677850D01*
X190137Y676650D01*
X190737Y675850D01*
X191437Y675650D01*
X192137Y676050D01*
X192837Y677250D01*
G01X196537Y675650D02*
Y685850D01*
X196737Y686850D01*
X197137Y687450D01*
X197737Y687650D01*
X198337Y687250D01*
X198637Y686250D01*
G01X197437Y682850D02*
X195437D01*
G01X201637Y681050D02*
X204837D01*
X204537Y682450D01*
X204037Y683250D01*
X203337Y683650D01*
X202637Y683450D01*
X202037Y682850D01*
X201637Y681450D01*
X201437Y680250D01*
Y679050D01*
X201637Y677850D01*
X202137Y676650D01*
X202737Y675850D01*
X203437Y675650D01*
X204137Y676050D01*
X204837Y677250D01*
G01X207737Y675650D02*
Y683650D01*
G01Y682050D02*
X208237Y682850D01*
X208737Y683450D01*
X209437Y683650D01*
X209937Y683450D01*
X210537Y682850D01*
G01X213637Y681050D02*
X216837D01*
X216537Y682450D01*
X216037Y683250D01*
X215337Y683650D01*
X214637Y683450D01*
X214037Y682850D01*
X213637Y681450D01*
X213437Y680250D01*
Y679050D01*
X213637Y677850D01*
X214137Y676650D01*
X214737Y675850D01*
X215437Y675650D01*
X216137Y676050D01*
X216837Y677250D01*
G01X219437Y675650D02*
Y683650D01*
G01Y681650D02*
X219837Y682650D01*
X220437Y683450D01*
X221237Y683650D01*
X221937Y683450D01*
X222537Y682650D01*
X222837Y681250D01*
Y675650D01*
G01X228737Y682650D02*
X228037Y683450D01*
X227437Y683650D01*
X226637Y683250D01*
X226037Y682450D01*
X225637Y681050D01*
X225537Y679650D01*
X225637Y678250D01*
X226037Y677050D01*
X226637Y676050D01*
X227437Y675650D01*
X228137Y676050D01*
X228737Y676850D01*
G01X231637Y681050D02*
X234837D01*
X234537Y682450D01*
X234037Y683250D01*
X233337Y683650D01*
X232637Y683450D01*
X232037Y682850D01*
X231637Y681450D01*
X231437Y680250D01*
Y679050D01*
X231637Y677850D01*
X232137Y676650D01*
X232737Y675850D01*
X233437Y675650D01*
X234137Y676050D01*
X234837Y677250D01*
G01X245137Y687650D02*
Y675650D01*
G01X243737Y683650D02*
X246537D01*
G01X251137Y675650D02*
X250537Y675850D01*
X249937Y676650D01*
X249537Y678050D01*
X249337Y679650D01*
X249537Y681250D01*
X249937Y682650D01*
X250537Y683450D01*
X251137Y683650D01*
X251737Y683450D01*
X252337Y682650D01*
X252737Y681250D01*
X252837Y679650D01*
X252737Y678050D01*
X252337Y676650D01*
X251737Y675850D01*
X251137Y675650D01*
G01X262537D02*
Y685850D01*
X262737Y686850D01*
X263137Y687450D01*
X263737Y687650D01*
X264337Y687250D01*
X264637Y686250D01*
G01X263437Y682850D02*
X261437D01*
G01X269137Y683650D02*
Y675650D01*
G01Y686850D02*
X268937Y687050D01*
Y687450D01*
X269137Y687650D01*
X269337Y687450D01*
Y687050D01*
X269137Y686850D01*
G01X273437Y675650D02*
Y683650D01*
G01Y681650D02*
X273837Y682650D01*
X274437Y683450D01*
X275237Y683650D01*
X275937Y683450D01*
X276537Y682650D01*
X276837Y681250D01*
Y675650D01*
G01X282937Y687650D02*
Y675650D01*
G01Y677450D02*
X282537Y676450D01*
X281937Y675850D01*
X281237Y675650D01*
X280437Y676050D01*
X279837Y677050D01*
X279437Y678250D01*
X279337Y679650D01*
X279437Y681050D01*
X279837Y682250D01*
X280437Y683250D01*
X281237Y683650D01*
X281937Y683450D01*
X282437Y683050D01*
X282937Y682250D01*
G01X293137Y687650D02*
Y675650D01*
G01X291737Y683650D02*
X294537D01*
G01X297437Y675650D02*
Y687650D01*
G01Y681850D02*
X297937Y682850D01*
X298437Y683450D01*
X299237Y683650D01*
X299837Y683450D01*
X300537Y682650D01*
X300837Y681450D01*
Y675650D01*
G01X303637Y681050D02*
X306837D01*
X306537Y682450D01*
X306037Y683250D01*
X305337Y683650D01*
X304637Y683450D01*
X304037Y682850D01*
X303637Y681450D01*
X303437Y680250D01*
Y679050D01*
X303637Y677850D01*
X304137Y676650D01*
X304737Y675850D01*
X305437Y675650D01*
X306137Y676050D01*
X306837Y677250D01*
G01X318937Y687650D02*
Y675650D01*
G01Y677450D02*
X318537Y676450D01*
X317937Y675850D01*
X317237Y675650D01*
X316437Y676050D01*
X315837Y677050D01*
X315437Y678250D01*
X315337Y679650D01*
X315437Y681050D01*
X315837Y682250D01*
X316437Y683250D01*
X317237Y683650D01*
X317937Y683450D01*
X318437Y683050D01*
X318937Y682250D01*
G01X323137Y683650D02*
Y675650D01*
G01Y686850D02*
X322937Y687050D01*
Y687450D01*
X323137Y687650D01*
X323337Y687450D01*
Y687050D01*
X323137Y686850D01*
G01X328537Y675650D02*
Y685850D01*
X328737Y686850D01*
X329137Y687450D01*
X329737Y687650D01*
X330337Y687250D01*
X330637Y686250D01*
G01X329437Y682850D02*
X327437D01*
G01X334537Y675650D02*
Y685850D01*
X334737Y686850D01*
X335137Y687450D01*
X335737Y687650D01*
X336337Y687250D01*
X336637Y686250D01*
G01X335437Y682850D02*
X333437D01*
G01X339637Y681050D02*
X342837D01*
X342537Y682450D01*
X342037Y683250D01*
X341337Y683650D01*
X340637Y683450D01*
X340037Y682850D01*
X339637Y681450D01*
X339437Y680250D01*
Y679050D01*
X339637Y677850D01*
X340137Y676650D01*
X340737Y675850D01*
X341437Y675650D01*
X342137Y676050D01*
X342837Y677250D01*
G01X345737Y675650D02*
Y683650D01*
G01Y682050D02*
X346237Y682850D01*
X346737Y683450D01*
X347437Y683650D01*
X347937Y683450D01*
X348537Y682850D01*
G01X351637Y681050D02*
X354837D01*
X354537Y682450D01*
X354037Y683250D01*
X353337Y683650D01*
X352637Y683450D01*
X352037Y682850D01*
X351637Y681450D01*
X351437Y680250D01*
Y679050D01*
X351637Y677850D01*
X352137Y676650D01*
X352737Y675850D01*
X353437Y675650D01*
X354137Y676050D01*
X354837Y677250D01*
G01X357437Y675650D02*
Y683650D01*
G01Y681650D02*
X357837Y682650D01*
X358437Y683450D01*
X359237Y683650D01*
X359937Y683450D01*
X360537Y682650D01*
X360837Y681250D01*
Y675650D01*
G01X365137Y687650D02*
Y675650D01*
G01X363737Y683650D02*
X366537D01*
G01X371137D02*
Y675650D01*
G01Y686850D02*
X370937Y687050D01*
Y687450D01*
X371137Y687650D01*
X371337Y687450D01*
Y687050D01*
X371137Y686850D01*
G01X378937Y675650D02*
Y683650D01*
G01Y682250D02*
X378537Y683050D01*
X377937Y683450D01*
X377237Y683650D01*
X376537Y683250D01*
X375937Y682450D01*
X375537Y681250D01*
X375337Y679650D01*
X375537Y678050D01*
X375937Y676850D01*
X376537Y676050D01*
X377237Y675650D01*
X377937Y675850D01*
X378537Y676450D01*
X378937Y677250D01*
G01X383137Y675650D02*
Y687650D01*
G01X395137D02*
Y675650D01*
G01X393737Y683650D02*
X396537D01*
G01X399737Y675650D02*
Y683650D01*
G01Y682050D02*
X400237Y682850D01*
X400737Y683450D01*
X401437Y683650D01*
X401937Y683450D01*
X402537Y682850D01*
G01X408937Y675650D02*
Y683650D01*
G01Y682250D02*
X408537Y683050D01*
X407937Y683450D01*
X407237Y683650D01*
X406537Y683250D01*
X405937Y682450D01*
X405537Y681250D01*
X405337Y679650D01*
X405537Y678050D01*
X405937Y676850D01*
X406537Y676050D01*
X407237Y675650D01*
X407937Y675850D01*
X408537Y676450D01*
X408937Y677250D01*
G01X414737Y682650D02*
X414037Y683450D01*
X413437Y683650D01*
X412637Y683250D01*
X412037Y682450D01*
X411637Y681050D01*
X411537Y679650D01*
X411637Y678250D01*
X412037Y677050D01*
X412637Y676050D01*
X413437Y675650D01*
X414137Y676050D01*
X414737Y676850D01*
G01X417637Y681050D02*
X420837D01*
X420537Y682450D01*
X420037Y683250D01*
X419337Y683650D01*
X418637Y683450D01*
X418037Y682850D01*
X417637Y681450D01*
X417437Y680250D01*
Y679050D01*
X417637Y677850D01*
X418137Y676650D01*
X418737Y675850D01*
X419437Y675650D01*
X420137Y676050D01*
X420837Y677250D01*
G01X423637Y677050D02*
X424137Y676250D01*
X424837Y675650D01*
X425437D01*
X426037Y676050D01*
X426437Y676650D01*
X426637Y677450D01*
X426537Y678650D01*
X426137Y679250D01*
X424337Y680450D01*
X423937Y681850D01*
X424137Y682850D01*
X424537Y683450D01*
X425137Y683650D01*
X425737Y683450D01*
X426337Y682850D01*
G01X437137Y683650D02*
Y675650D01*
G01Y686850D02*
X436937Y687050D01*
Y687450D01*
X437137Y687650D01*
X437337Y687450D01*
Y687050D01*
X437137Y686850D01*
G01X441437Y675650D02*
Y683650D01*
G01Y681650D02*
X441837Y682650D01*
X442437Y683450D01*
X443237Y683650D01*
X443937Y683450D01*
X444537Y682650D01*
X444837Y681250D01*
Y675650D01*
G01X455137D02*
Y687650D01*
G01X462937Y675650D02*
Y683650D01*
G01Y682250D02*
X462537Y683050D01*
X461937Y683450D01*
X461237Y683650D01*
X460537Y683250D01*
X459937Y682450D01*
X459537Y681250D01*
X459337Y679650D01*
X459537Y678050D01*
X459937Y676850D01*
X460537Y676050D01*
X461237Y675650D01*
X461937Y675850D01*
X462537Y676450D01*
X462937Y677250D01*
G01X465037Y672050D02*
X465637Y671650D01*
X466437Y672050D01*
X466937Y672850D01*
X467337Y673850D01*
X467937Y677050D01*
X469237Y683650D01*
G01X466037D02*
X467937Y677050D01*
G01X471637Y681050D02*
X474837D01*
X474537Y682450D01*
X474037Y683250D01*
X473337Y683650D01*
X472637Y683450D01*
X472037Y682850D01*
X471637Y681450D01*
X471437Y680250D01*
Y679050D01*
X471637Y677850D01*
X472137Y676650D01*
X472737Y675850D01*
X473437Y675650D01*
X474137Y676050D01*
X474837Y677250D01*
G01X477737Y675650D02*
Y683650D01*
G01Y682050D02*
X478237Y682850D01*
X478737Y683450D01*
X479437Y683650D01*
X479937Y683450D01*
X480537Y682850D01*
G01X491937Y682050D02*
X492337Y682650D01*
X492637Y683650D01*
X492837Y685050D01*
X492637Y686250D01*
X492237Y687050D01*
X491537Y687650D01*
X488837D01*
Y675650D01*
X492137D01*
X492837Y676450D01*
X493237Y677650D01*
X493437Y679050D01*
X493237Y680450D01*
X492637Y681650D01*
X491937Y682050D01*
X488837D01*
G01X497137Y675650D02*
X496337Y675850D01*
X495637Y676650D01*
X495037Y677850D01*
X494637Y679250D01*
X494437Y680850D01*
Y682450D01*
X494637Y684050D01*
X495037Y685450D01*
X495637Y686650D01*
X496337Y687450D01*
X497137Y687650D01*
X497937Y687450D01*
X498637Y686650D01*
X499237Y685450D01*
X499637Y684050D01*
X499837Y682450D01*
Y680850D01*
X499637Y679250D01*
X499237Y677850D01*
X498637Y676650D01*
X497937Y675850D01*
X497137Y675650D01*
G01X503137Y687650D02*
Y675650D01*
G01X500837Y687650D02*
X505437D01*
G01X509137D02*
Y675650D01*
G01X506837Y687650D02*
X511437D01*
G01X515137Y675650D02*
X514337Y675850D01*
X513637Y676650D01*
X513037Y677850D01*
X512637Y679250D01*
X512437Y680850D01*
Y682450D01*
X512637Y684050D01*
X513037Y685450D01*
X513637Y686650D01*
X514337Y687450D01*
X515137Y687650D01*
X515937Y687450D01*
X516637Y686650D01*
X517237Y685450D01*
X517637Y684050D01*
X517837Y682450D01*
Y680850D01*
X517637Y679250D01*
X517237Y677850D01*
X516637Y676650D01*
X515937Y675850D01*
X515137Y675650D01*
G01X518537D02*
Y687650D01*
X521137Y677650D01*
X523737Y687650D01*
Y675650D01*
G01X26377Y-1D02*
Y46062D01*
G01D02*
G03X22440Y49999I-3937J0D01*
G01X102756Y290550D02*
G03Y298424I0J3937D01*
G01X133465D02*
G03Y290550I0J-3937D01*
G01X299606Y290551D02*
G03Y298425I0J3937D01*
G01X330314D02*
G03Y290551I0J-3937D01*
G01X353350Y224807D02*
X347051D01*
G02Y237406I0J6299D01*
G01X353350D01*
G02Y224807I0J-6299D01*
G01X496457Y290550D02*
G03Y298424I0J3937D01*
G01X527166D02*
G03Y290550I0J-3937D01*
G01X693308D02*
G03Y298424I0J3937D01*
G01X724016D02*
G03Y290550I0J-3937D01*
G01X800393Y588976D02*
Y542913D01*
G01D02*
G03X804330Y538976I3937J0D01*
G01X858267Y588976D02*
X800393D01*
G01X804330Y538976D02*
X830708D01*
G01X834645Y72440D02*
G03X826771I-3937J0D01*
G01Y103149D02*
G03X834645I3937J0D01*
G01Y210235D02*
G03X826771I-3937J0D01*
G01Y240944D02*
G03X834645I3937J0D01*
G01Y348031D02*
G03X826771I-3937J0D01*
G01Y378739D02*
G03X834645I3937J0D01*
G01Y485826D02*
G03X826771I-3937J0D01*
G01Y516535D02*
G03X834645I3937J-1D01*
G01Y535039D02*
G03X830708Y538976I-3937J0D01*
G01X834645Y72440D02*
Y-1D01*
G01D02*
X858267D01*
G01X853444Y15747D02*
G03I-6988J0D01*
G01X834645Y210235D02*
Y103149D01*
G01Y348031D02*
Y240944D01*
G01Y485826D02*
Y378739D01*
G01Y535039D02*
Y516535D01*
G01X853444Y573227D02*
G03I-6988J0D01*
G01X862204Y3936D02*
Y585039D01*
G01X858267Y-1D02*
G03X862204Y3936I0J3937D01*
G01Y585039D02*
G03X858267Y588976I-3937J0D01*
G54D13*
G01X517726Y10281D02*
Y21864D01*
G01X518307Y9700D02*
X517726Y10281D01*
G01X518307Y6656D02*
Y9700D01*
G01X516526Y10233D02*
Y21865D01*
G01X515945Y9652D02*
X516526Y10233D01*
G01X515945Y6656D02*
Y9652D01*
G01X517726Y21864D02*
X518769Y22907D01*
G01X516526Y21865D02*
X515484Y22907D01*
G01X518889Y263532D02*
X517846Y262489D01*
G01X518889Y275237D02*
Y263532D01*
G01X520089Y263531D02*
X521131Y262489D01*
G01X520089Y275141D02*
Y263531D01*
G01X520670Y275722D02*
X520089Y275141D01*
G01X518307Y275819D02*
X518889Y275237D01*
G01X518307Y278740D02*
Y275819D01*
G01X520670Y278740D02*
Y275722D01*
G01X535442Y23950D02*
X536485Y22907D01*
G01X535442Y35349D02*
Y23950D01*
G01X534242Y23949D02*
X533200Y22907D01*
G01X534242Y35365D02*
Y23949D01*
G01X536023Y35930D02*
X535442Y35349D01*
G01X536023Y38940D02*
Y35930D01*
G01X533661Y35946D02*
X534242Y35365D01*
G01X533661Y38940D02*
Y35946D01*
G01X536798Y250350D02*
Y261253D01*
G01X536024Y249576D02*
X536798Y250350D01*
G01X536024Y246456D02*
Y249576D01*
G01X537998Y250164D02*
Y261640D01*
G01X538386Y249776D02*
X537998Y250164D01*
G01X538386Y246456D02*
Y249776D01*
G01X536798Y261253D02*
X535562Y262489D01*
G01X537998Y261640D02*
X538847Y262489D01*
G01X556702Y23950D02*
X557745Y22907D01*
G01X556702Y35409D02*
Y23950D01*
G01X555502Y23949D02*
X554460Y22907D01*
G01X555502Y35305D02*
Y23949D01*
G01X557283Y35990D02*
X556702Y35409D01*
G01X554921Y35886D02*
X555502Y35305D01*
G01X554921Y38940D02*
Y35886D01*
G01X556684Y263532D02*
X555641Y262489D01*
G01X556684Y275042D02*
Y263532D01*
G01X556103Y275623D02*
X556684Y275042D01*
G01X556103Y278740D02*
Y275623D01*
G01X557283Y38940D02*
Y35990D01*
G01X557884Y263531D02*
X558926Y262489D01*
G01X557884Y275089D02*
Y263531D01*
G01X558465Y275670D02*
X557884Y275089D01*
G01X558465Y278740D02*
Y275670D01*
G01X576781Y10126D02*
Y21864D01*
G01X577362Y9545D02*
X576781Y10126D01*
G01X577362Y6656D02*
Y9545D01*
G01X575581Y10288D02*
Y21865D01*
G01X575000Y9707D02*
X575581Y10288D01*
G01X575000Y6656D02*
Y9707D01*
G01X576781Y21864D02*
X577824Y22907D01*
G01X575581Y21865D02*
X574539Y22907D01*
G01X574400Y250052D02*
Y261446D01*
G01X573819Y249471D02*
X574400Y250052D01*
G01X573819Y246456D02*
Y249471D01*
G01X575600Y249926D02*
Y261447D01*
G01X576181Y249345D02*
X575600Y249926D01*
G01X576181Y246456D02*
Y249345D01*
G01X574400Y261446D02*
X573357Y262489D01*
G01X575600Y261447D02*
X576642Y262489D01*
G01X602746Y23949D02*
X601704Y22907D01*
G01X602746Y34071D02*
Y23949D01*
G01X602165Y34652D02*
X602746Y34071D01*
G01X602165Y38940D02*
Y34652D01*
G01X603946Y23950D02*
X604989Y22907D01*
G01X603946Y34071D02*
Y23950D01*
G01X604527Y34652D02*
X603946Y34071D01*
G01X604527Y38940D02*
Y34652D01*
G01X649991Y261446D02*
X648948Y262489D01*
G01X649991Y251325D02*
Y261446D01*
G01X649410Y250744D02*
X649991Y251325D01*
G01X649410Y246456D02*
Y250744D01*
G01X651191Y251325D02*
Y261447D01*
G01X651772Y250744D02*
X651191Y251325D01*
G01X651772Y246456D02*
Y250744D01*
G01X651191Y261447D02*
X652233Y262489D01*
G01X679537Y23850D02*
X680580Y22807D01*
G01X679537Y35344D02*
Y23850D01*
G01X678337Y23849D02*
X677295Y22807D01*
G01X678337Y35470D02*
Y23849D01*
G01X680118Y35925D02*
X679537Y35344D01*
G01X677756Y36051D02*
X678337Y35470D01*
G01X677756Y38940D02*
Y36051D01*
G01X677156Y263532D02*
X676113Y262489D01*
G01X677156Y275270D02*
Y263532D01*
G01X678356Y263531D02*
X679398Y262489D01*
G01X678356Y275108D02*
Y263531D01*
G01X678937Y275689D02*
X678356Y275108D01*
G01X676575Y275851D02*
X677156Y275270D01*
G01X676575Y278740D02*
Y275851D01*
G01X678937Y278740D02*
Y275689D01*
G01X695472Y9726D02*
X696053Y10307D01*
G01X695472Y6656D02*
Y9726D01*
G01X696053Y21829D02*
X695029Y22853D01*
G01X680118Y38940D02*
Y35925D01*
G01X697253Y10354D02*
Y21831D01*
G01X697834Y9773D02*
X697253Y10354D01*
G01X697834Y6656D02*
Y9773D01*
G01X696053Y10307D02*
Y21829D01*
G01X697253Y21831D02*
X698277Y22855D01*
G01X697600Y254298D02*
Y261081D01*
G01X696805Y253503D02*
X697600Y254298D01*
G01X696805Y249557D02*
Y253503D01*
G01X696654Y249406D02*
X696805Y249557D01*
G01X696654Y246456D02*
Y249406D01*
G01X698800Y253800D02*
Y261812D01*
G01X698005Y253005D02*
X698800Y253800D01*
G01X698005Y250521D02*
Y253005D01*
G01X699016Y249510D02*
X698005Y250521D01*
G01X699016Y246456D02*
Y249510D01*
G01X697600Y261081D02*
X696192Y262489D01*
G01X698800Y261812D02*
X699477Y262489D01*
G01X717600Y23682D02*
X718375Y22907D01*
G01X717600Y29007D02*
Y23682D01*
G01X716400Y24217D02*
X715090Y22907D01*
G01X716400Y28509D02*
Y24217D01*
G01X715351Y29558D02*
X716400Y28509D01*
G01X716551Y30056D02*
X717600Y29007D01*
G01X716551Y34458D02*
Y30056D01*
G01X717913Y35820D02*
X716551Y34458D01*
G01X717913Y38940D02*
Y35820D01*
G01X715351Y34956D02*
Y29558D01*
G01X715551Y35156D02*
X715351Y34956D01*
G01X715551Y38940D02*
Y35156D01*
G01X718495Y250047D02*
Y261446D01*
G01X717914Y249466D02*
X718495Y250047D01*
G01X717914Y246456D02*
Y249466D01*
G01X719695Y250031D02*
Y261447D01*
G01X720276Y249450D02*
X719695Y250031D01*
G01X720276Y246456D02*
Y249450D01*
G01X718495Y261446D02*
X717452Y262489D01*
G01X719695Y261447D02*
X720737Y262489D01*
G01X735048Y10159D02*
Y22564D01*
G01X735630Y9577D02*
X735048Y10159D01*
G01X735630Y6656D02*
Y9577D01*
G01X733848Y10255D02*
Y22565D01*
G01X733267Y9674D02*
X733848Y10255D01*
G01X733267Y6656D02*
Y9674D01*
G01X735048Y22564D02*
X736091Y23607D01*
G01X733848Y22565D02*
X732806Y23607D01*
G01X736211Y263532D02*
X735168Y262489D01*
G01X736211Y275115D02*
Y263532D01*
G01X735630Y275696D02*
X736211Y275115D01*
G01X737411Y263531D02*
X738453Y262489D01*
G01X737411Y275163D02*
Y263531D01*
G01X737992Y275744D02*
X737411Y275163D01*
G01X735630Y278740D02*
Y275696D01*
G01X737992Y278740D02*
Y275744D01*
G54D14*
G01X10800Y189700D02*
Y200140D01*
G01X15300Y185200D02*
X10800Y189700D01*
G01X49600Y185200D02*
X15300D01*
G01X9450Y189140D02*
Y210460D01*
G01X14740Y183850D02*
X9450Y189140D01*
G01X49040Y183850D02*
X14740D01*
G01X14412Y212395D02*
Y213512D01*
G01X13246Y211228D02*
X14412Y212395D01*
G01X12128Y211228D02*
X13246D01*
G01X10800Y209900D02*
X12128Y211228D01*
G01X10800Y208250D02*
Y209900D01*
G01X11590Y207460D02*
X10800Y208250D01*
G01X11590Y205810D02*
Y207460D01*
G01X10800Y205020D02*
X11590Y205810D01*
G01X10800Y203370D02*
Y205020D01*
G01X11590Y202580D02*
X10800Y203370D01*
G01X11590Y200930D02*
Y202580D01*
G01X10800Y200140D02*
X11590Y200930D01*
G01X9450Y210460D02*
X15019Y216029D01*
G01X15579Y214679D02*
X18821D01*
G01X14412Y213512D02*
X15579Y214679D01*
G01X15019Y216029D02*
X18700D01*
G01X14300Y232339D02*
X13090Y231129D01*
G01X19000Y232339D02*
X14300D01*
G01Y233689D02*
X13090Y234899D01*
G01X19000Y233689D02*
X14300D01*
G01X14800Y244150D02*
X13590Y242940D01*
G01X17791Y244150D02*
X14800D01*
G01X8810Y238301D02*
X7600Y237091D01*
G01X17735Y238301D02*
X8810D01*
G01Y239651D02*
X7600Y240861D01*
G01X17735Y239651D02*
X8810D01*
G01X14800Y245500D02*
X13590Y246710D01*
G01X17679Y245500D02*
X14800D01*
G01Y257311D02*
X13590Y258521D01*
G01X18800Y257311D02*
X14800D01*
G01Y255961D02*
X13590Y254751D01*
G01X19000Y255961D02*
X14800D01*
G01X8810Y250112D02*
X7600Y248902D01*
G01X17735Y250112D02*
X8810D01*
G01Y251462D02*
X7600Y252672D01*
G01X17735Y251462D02*
X8810D01*
G01Y261923D02*
X7600Y260713D01*
G01X17735Y261923D02*
X8810D01*
G01Y263273D02*
X7600Y264483D01*
G01X17735Y263273D02*
X8810D01*
G01X27000Y202090D02*
Y219700D01*
G01X28440Y200650D02*
X27000Y202090D01*
G01X30650Y200650D02*
X28440D01*
G01X32000Y199300D02*
X30650Y200650D01*
G01X28350Y202650D02*
Y220260D01*
G01X29000Y202000D02*
X28350Y202650D01*
G01X30800Y202000D02*
X29000D01*
G01X32000Y203200D02*
X30800Y202000D01*
G01X31000Y211040D02*
Y221900D01*
G01X32390Y209650D02*
X31000Y211040D01*
G01X33450Y209650D02*
X32390D01*
G01X32350Y211600D02*
Y222460D01*
G01X32950Y211000D02*
X32350Y211600D01*
G01X24775Y220275D02*
X21949D01*
G01X25084Y220584D02*
X24775Y220275D01*
G01X26116Y220584D02*
X25084D01*
G01X27000Y219700D02*
X26116Y220584D01*
G01X24756Y222244D02*
X21949D01*
G01X25066Y221934D02*
X24756Y222244D01*
G01X26676Y221934D02*
X25066D01*
G01X28350Y220260D02*
X26676Y221934D01*
G01X24781Y226181D02*
X21949D01*
G01X25090Y226490D02*
X24781Y226181D01*
G01X26410Y226490D02*
X25090D01*
G01X31000Y221900D02*
X26410Y226490D01*
G01X24551Y228149D02*
X21949D01*
G01X24860Y227840D02*
X24551Y228149D01*
G01X26970Y227840D02*
X24860D01*
G01X32350Y222460D02*
X26970Y227840D01*
G01X19130Y214370D02*
X21949D01*
G01X18821Y214679D02*
X19130Y214370D01*
G01X19009Y216338D02*
X21949D01*
G01X18700Y216029D02*
X19009Y216338D01*
G01X19253Y232086D02*
X19000Y232339D01*
G01X21949Y232086D02*
X19253D01*
G01X19366Y234055D02*
X19000Y233689D01*
G01X21949Y234055D02*
X19366D01*
G01X18044Y243897D02*
X17791Y244150D01*
G01X21949Y243897D02*
X18044D01*
G01Y237992D02*
X17735Y238301D01*
G01X21949Y237992D02*
X18044D01*
G01Y239960D02*
X17735Y239651D01*
G01X21949Y239960D02*
X18044D01*
G01X18045Y245866D02*
X17679Y245500D01*
G01X21949Y245866D02*
X18045D01*
G01X19166Y257677D02*
X18800Y257311D01*
G01X21949Y257677D02*
X19166D01*
G01X19253Y255708D02*
X19000Y255961D01*
G01X21949Y255708D02*
X19253D01*
G01X18044Y249803D02*
X17735Y250112D01*
G01X21949Y249803D02*
X18044D01*
G01Y251771D02*
X17735Y251462D01*
G01X21949Y251771D02*
X18044D01*
G01Y261614D02*
X17735Y261923D01*
G01X21949Y261614D02*
X18044D01*
G01Y263582D02*
X17735Y263273D01*
G01X21949Y263582D02*
X18044D01*
G01X34800Y208300D02*
X33450Y209650D01*
G01X33600Y211000D02*
X32950D01*
G01X34800Y212200D02*
X33600Y211000D01*
G01X52400Y182400D02*
X49600Y185200D01*
G01X58500Y182400D02*
X52400D01*
G01X70850Y170050D02*
X58500Y182400D01*
G01X51840Y181050D02*
X49040Y183850D01*
G01X57940Y181050D02*
X51840D01*
G01X70290Y168700D02*
X57940Y181050D01*
G01X68307Y22892D02*
Y33257D01*
G01X72244Y22892D02*
Y33256D01*
G01X69600Y41100D02*
X72500Y44000D01*
G01X69600Y34550D02*
Y41100D01*
G01X68307Y33257D02*
X69600Y34550D01*
G01X73060Y42650D02*
X80150D01*
G01X70950Y40540D02*
X73060Y42650D01*
G01X70950Y34550D02*
Y40540D01*
G01X72244Y33256D02*
X70950Y34550D01*
G01X72500Y44000D02*
X79590D01*
G01X80325Y59769D02*
X79115Y60979D01*
G01X75863Y170050D02*
X70850D01*
G01X76653Y170840D02*
X75863Y170050D01*
G01X78303Y170840D02*
X76653D01*
G01X79093Y170050D02*
X78303Y170840D01*
G01X87690Y168700D02*
X70290D01*
G01X87992Y22892D02*
Y33256D01*
G01X84055Y22892D02*
Y33257D01*
G01X87700Y42200D02*
Y47400D01*
G01X86698Y41198D02*
X87700Y42200D01*
G01X86698Y34550D02*
Y41198D01*
G01X87992Y33256D02*
X86698Y34550D01*
G01X86350Y42760D02*
Y47350D01*
G01X85348Y41758D02*
X86350Y42760D01*
G01X85348Y34550D02*
Y41758D01*
G01X84055Y33257D02*
X85348Y34550D01*
G01X80150Y42650D02*
X81700Y44200D01*
G01X87700Y47400D02*
X88500Y48200D01*
G01Y54200D02*
X88700Y54400D01*
G01X88500Y51800D02*
Y54200D01*
G01X85500D02*
X85300Y54400D01*
G01X85500Y51800D02*
Y54200D01*
G01X86350Y47350D02*
X85500Y48200D01*
G01X80350Y47350D02*
X79500Y48200D01*
G01X80350Y44760D02*
Y47350D01*
G01X79590Y44000D02*
X80350Y44760D01*
G01X80325Y52625D02*
Y59769D01*
G01X79500Y51800D02*
X80325Y52625D01*
G01X81675D02*
Y59769D01*
G01X82500Y51800D02*
X81675Y52625D01*
G01X81700Y47400D02*
X82500Y48200D01*
G01X81700Y44200D02*
Y47400D01*
G01X81675Y59769D02*
X82885Y60979D01*
G01X103175Y155125D02*
X88250Y170050D01*
G01X102615Y153775D02*
X87690Y168700D01*
G01X88250Y170050D02*
X79093D01*
G01X103740Y22892D02*
Y33256D01*
G01X99803Y22892D02*
Y33257D01*
G01X102446Y34550D02*
Y47396D01*
G01X103740Y33256D02*
X102446Y34550D01*
G01X101096D02*
Y47354D01*
G01X99803Y33257D02*
X101096Y34550D01*
G01X102446Y47396D02*
X103250Y48200D01*
G01Y54200D02*
X103450Y54400D01*
G01X103250Y51800D02*
Y54200D01*
G01X100250D02*
X100050Y54400D01*
G01X100250Y51800D02*
Y54200D01*
G01X101096Y47354D02*
X100250Y48200D01*
G01X115785Y155125D02*
X103175D01*
G01X115225Y153775D02*
X102615D01*
G01X119488Y22892D02*
Y33256D01*
G01X115551Y22892D02*
Y33257D01*
G01X118194Y34550D02*
Y47394D01*
G01X119488Y33256D02*
X118194Y34550D01*
G01X116844D02*
Y47356D01*
G01X115551Y33257D02*
X116844Y34550D01*
G01X118194Y47394D02*
X119000Y48200D01*
G01X118175Y56375D02*
X119200Y57400D01*
G01X118175Y52625D02*
Y56375D01*
G01X119000Y51800D02*
X118175Y52625D01*
G01X116825Y56375D02*
X115800Y57400D01*
G01X116825Y52625D02*
Y56375D01*
G01X116000Y51800D02*
X116825Y52625D01*
G01X116844Y47356D02*
X116000Y48200D01*
G01X112017Y56988D02*
Y66383D01*
G01D02*
X111200Y67200D01*
G01X123785Y147125D02*
X115785Y155125D01*
G01X135085Y147125D02*
X123785D01*
G01X123225Y145775D02*
X115225Y153775D01*
G01X134525Y145775D02*
X123225D01*
G01X135236Y22892D02*
Y33256D01*
G01X131299Y22892D02*
Y33257D01*
G01X133942Y34550D02*
Y47342D01*
G01X135236Y33256D02*
X133942Y34550D01*
G01X132592D02*
Y47408D01*
G01X131299Y33257D02*
X132592Y34550D01*
G01X133975Y56375D02*
X135000Y57400D01*
G01X133975Y52625D02*
Y56375D01*
G01X134800Y51800D02*
X133975Y52625D01*
G01X133942Y47342D02*
X134800Y48200D01*
G01X132592Y47408D02*
X131800Y48200D01*
G01X132625Y56375D02*
X131600Y57400D01*
G01X132625Y52625D02*
Y56375D01*
G01X131800Y51800D02*
X132625Y52625D01*
G01X140000Y93300D02*
Y142210D01*
G01X141500Y91800D02*
X140000Y93300D01*
G01X138650Y92740D02*
Y141650D01*
G01X140940Y90450D02*
X138650Y92740D01*
G01X140000Y142210D02*
X135085Y147125D01*
G01X138650Y141650D02*
X134525Y145775D01*
G01X150984Y22892D02*
Y33256D01*
G01X147047Y22892D02*
Y33257D01*
G01X149690Y34550D02*
Y47375D01*
G01X150984Y33256D02*
X149690Y34550D01*
G01X148340D02*
Y47375D01*
G01X147047Y33257D02*
X148340Y34550D01*
G01X150515Y54200D02*
X150715Y54400D01*
G01X150515Y51800D02*
Y54200D01*
G01X149690Y47375D02*
X150515Y48200D01*
G01X148340Y47375D02*
X147515Y48200D01*
G01Y54200D02*
X147315Y54400D01*
G01X147515Y51800D02*
Y54200D01*
G01X155290Y48610D02*
X156500Y49820D01*
G01X154235Y91675D02*
X160560Y85350D01*
G01X153675Y90325D02*
X160000Y84000D01*
G01X150200Y89500D02*
X151025Y90325D01*
G01X143800Y89500D02*
X143500Y89200D01*
G01X146800Y89500D02*
X143800D01*
G01X143500Y89200D02*
X142250Y90450D01*
G01X151025Y91675D02*
X154235D01*
G01X150200Y92500D02*
X151025Y91675D01*
G01Y90325D02*
X153675D01*
G01X143800Y92500D02*
X143500Y92800D01*
G01X146800Y92500D02*
X143800D01*
G01X142500Y91800D02*
X141500D01*
G01X143500Y92800D02*
X142500Y91800D01*
G01X142250Y90450D02*
X140940D01*
G01X146000Y118340D02*
Y125610D01*
G01X147840Y116500D02*
X146000Y118340D01*
G01X149670Y116500D02*
X147840D01*
G01X150670Y115500D02*
X149670Y116500D01*
G01X149620Y117850D02*
X150670Y118900D01*
G01X148400Y117850D02*
X149620D01*
G01X147350Y118900D02*
X148400Y117850D01*
G01X147350Y125050D02*
Y118900D01*
G01X146000Y125610D02*
X162590Y142200D01*
G01X151998Y129698D02*
X147350Y125050D01*
G01X153115Y129698D02*
X151998D01*
G01X154282Y130865D02*
X153115Y129698D01*
G01X154282Y131982D02*
Y130865D01*
G01X155449Y133149D02*
X154282Y131982D01*
G01X156566Y133149D02*
X155449D01*
G01X166732Y22892D02*
Y33256D01*
G01X162795Y22892D02*
Y33257D01*
G01X165438Y34550D02*
Y47375D01*
G01X166732Y33256D02*
X165438Y34550D01*
G01X164088D02*
Y47375D01*
G01X162795Y33257D02*
X164088Y34550D01*
G01X166263Y54200D02*
X166463Y54400D01*
G01X166263Y51800D02*
Y54200D01*
G01X165438Y47375D02*
X166263Y48200D01*
G01X164088Y47375D02*
X163263Y48200D01*
G01Y54200D02*
X163063Y54400D01*
G01X163263Y51800D02*
Y54200D01*
G01X160000Y57800D02*
X160300Y57500D01*
G01X160000Y60900D02*
Y57800D01*
G01X159175Y56375D02*
X160300Y57500D01*
G01X159175Y54175D02*
Y56375D01*
G01X157850Y52850D02*
X159175Y54175D01*
G01X157850Y49820D02*
Y52850D01*
G01X159060Y48610D02*
X157850Y49820D01*
G01X157000Y57800D02*
X156700Y57500D01*
G01X157000Y60900D02*
Y57800D01*
G01X157825Y56375D02*
X156700Y57500D01*
G01X157825Y54735D02*
Y56375D01*
G01X156500Y53410D02*
X157825Y54735D01*
G01X156500Y49820D02*
Y53410D01*
G01X171500Y50810D02*
X170290Y49600D01*
G01X165425Y70925D02*
Y73450D01*
G01X165115Y70615D02*
X165425Y70925D01*
G01X165115Y69215D02*
Y70615D01*
G01X163162Y67262D02*
X165115Y69215D01*
G01X160037Y67262D02*
X163162D01*
G01X159175Y66400D02*
X160037Y67262D01*
G01X159175Y65125D02*
Y66400D01*
G01X160000Y64300D02*
X159175Y65125D01*
G01X163455Y70945D02*
Y73450D01*
G01X163765Y70635D02*
X163455Y70945D01*
G01X163765Y69775D02*
Y70635D01*
G01X162602Y68612D02*
X163765Y69775D01*
G01X159477Y68612D02*
X162602D01*
G01X157825Y66960D02*
X159477Y68612D01*
G01X157825Y65125D02*
Y66960D01*
G01X157000Y64300D02*
X157825Y65125D01*
G01X171335Y71010D02*
Y73450D01*
G01X171645Y70700D02*
X171335Y71010D01*
G01X170800Y67800D02*
X171645Y68645D01*
G01X170700Y61300D02*
X171500Y60500D01*
G01X170800Y61400D02*
X170700Y61300D01*
G01X170800Y64400D02*
Y61400D01*
G01X160560Y85350D02*
X182060D01*
G01X160000Y84000D02*
X181500D01*
G01X167395Y106195D02*
Y101750D01*
G01X165425Y106175D02*
Y101750D01*
G01X167900Y106700D02*
X167395Y106195D01*
G01X164900Y106700D02*
X165425Y106175D01*
G01X167075Y114125D02*
X168000Y113200D01*
G01X167075Y117105D02*
Y114125D01*
G01X167865Y117895D02*
X167075Y117105D01*
G01X167865Y119545D02*
Y117895D01*
G01X167075Y120335D02*
X167865Y119545D01*
G01X167075Y121985D02*
Y120335D01*
G01X167900Y113100D02*
X168000Y113200D01*
G01X167900Y110100D02*
Y113100D01*
G01X164900D02*
X164800Y113200D01*
G01X164900Y110100D02*
Y113100D01*
G01X165725Y114125D02*
Y127425D01*
G01X164800Y113200D02*
X165725Y114125D01*
G01X157733Y134315D02*
X156566Y133149D01*
G01X157733Y135433D02*
Y134315D01*
G01X158899Y136599D02*
X157733Y135433D01*
G01X167865Y122775D02*
X167075Y121985D01*
G01X167865Y124425D02*
Y122775D01*
G01X167075Y125215D02*
X167865Y124425D01*
G01X167075Y126865D02*
Y125215D01*
G01X173560Y133350D02*
X167075Y126865D01*
G01X165725Y127425D02*
X173000Y134700D01*
G01X162590Y142200D02*
X178500D01*
G01X160017Y136599D02*
X158899D01*
G01X161183Y137766D02*
X160017Y136599D01*
G01X161183Y138883D02*
Y137766D01*
G01X163150Y140850D02*
X161183Y138883D01*
G01X167932Y140850D02*
X163150D01*
G01X168722Y140060D02*
X167932Y140850D01*
G01X170372Y140060D02*
X168722D01*
G01X171162Y140850D02*
X170372Y140060D01*
G01X179060Y140850D02*
X171162D01*
G01X168350Y175050D02*
X167140Y173840D01*
G01X168350Y176360D02*
Y175050D01*
G01X169940Y177950D02*
X168350Y176360D01*
G01X173940Y177950D02*
X169940D01*
G01X169700Y175050D02*
X170910Y173840D01*
G01X169700Y175800D02*
Y175050D01*
G01X170500Y176600D02*
X169700Y175800D01*
G01X174500Y176600D02*
X170500D01*
G01X182480Y22892D02*
Y33256D01*
G01X178543Y22892D02*
Y33257D01*
G01X181186Y34550D02*
Y47386D01*
G01X182480Y33256D02*
X181186Y34550D01*
G01X179836D02*
Y47364D01*
G01X178543Y33257D02*
X179836Y34550D01*
G01X182000Y54200D02*
X181800Y54400D01*
G01X182000Y51800D02*
Y54200D01*
G01X181186Y47386D02*
X182000Y48200D01*
G01X179836Y47364D02*
X179000Y48200D01*
G01Y51800D02*
Y54400D01*
G01X187375Y54810D02*
X186865Y54300D01*
G01X186200Y57500D02*
X187375Y56325D01*
G01X186500Y57800D02*
X186200Y57500D01*
G01X186500Y60900D02*
Y57800D01*
G01X172850Y50810D02*
X174060Y49600D01*
G01X172850Y60250D02*
Y50810D01*
G01X171500Y60500D02*
Y50810D01*
G01X181185Y71210D02*
Y73450D01*
G01X180875Y70900D02*
X181185Y71210D01*
G01X180875Y69500D02*
Y70900D01*
G01X181912Y68463D02*
X180875Y69500D01*
G01X187172Y68463D02*
X181912D01*
G01X179215Y71085D02*
Y73450D01*
G01X179525Y70775D02*
X179215Y71085D01*
G01X179525Y68940D02*
Y70775D01*
G01X181352Y67113D02*
X179525Y68940D01*
G01X186612Y67113D02*
X181352D01*
G01X187325Y66400D02*
X186612Y67113D01*
G01X186500Y64300D02*
X187325Y65125D01*
G01X173305Y71010D02*
Y73450D01*
G01X172995Y70700D02*
X173305Y71010D01*
G01X172995Y68605D02*
Y70700D01*
G01X173800Y67800D02*
X172995Y68605D01*
G01X171645Y68645D02*
Y70700D01*
G01X173900Y61300D02*
X172850Y60250D01*
G01X173800Y61400D02*
X173900Y61300D01*
G01X173800Y64400D02*
Y61400D01*
G01X182060Y85350D02*
X188800Y78610D01*
G01X181500Y84000D02*
X187450Y78050D01*
G01X178740Y133350D02*
X173560D01*
G01X182266Y129824D02*
X178740Y133350D01*
G01X183916Y129824D02*
X182266D01*
G01X184706Y129034D02*
X183916Y129824D01*
G01X186356Y129034D02*
X184706D01*
G01X187146Y129824D02*
X186356Y129034D01*
G01X182826Y131174D02*
X195964D01*
G01X179300Y134700D02*
X182826Y131174D01*
G01X173000Y134700D02*
X179300D01*
G01X178500Y142200D02*
X188600Y152300D01*
G01X189950Y151740D02*
X179060Y140850D01*
G01X178371Y174112D02*
X177159Y172900D01*
G01X178371Y176871D02*
Y174112D01*
G01X179759Y178259D02*
X178371Y176871D01*
G01X179759Y181448D02*
Y178259D01*
G01X179721Y174195D02*
X180931Y172985D01*
G01X179721Y176311D02*
Y174195D01*
G01X181109Y177699D02*
X179721Y176311D01*
G01X181109Y178422D02*
Y177699D01*
G01X181333Y178646D02*
X181109Y178422D01*
G01X181333Y181448D02*
Y178646D01*
G01X186058Y179440D02*
Y181448D01*
G01X189200Y176298D02*
X186058Y179440D01*
G01X175147Y179157D02*
X173940Y177950D01*
G01X175147Y179853D02*
Y179157D01*
G01X175034Y179966D02*
X175147Y179853D01*
G01X175034Y181448D02*
Y179966D01*
G01X176497Y178597D02*
X174500Y176600D01*
G01X176497Y180000D02*
Y178597D01*
G01X176609Y180112D02*
X176497Y180000D01*
G01X176609Y181448D02*
Y180112D01*
G01X183875Y211085D02*
X188740Y215950D01*
G01X183875Y208845D02*
Y211085D01*
G01X181333Y206303D02*
X183875Y208845D01*
G01X181333Y203570D02*
Y206303D01*
G01X185225Y210525D02*
X189300Y214600D01*
G01X185225Y208285D02*
Y210525D01*
G01X182908Y205968D02*
X185225Y208285D01*
G01X182908Y203570D02*
Y205968D01*
G01X186058Y205758D02*
X192350Y212050D01*
G01X186058Y203570D02*
Y205758D01*
G01X194291Y22892D02*
Y33257D01*
G01X198228Y22892D02*
Y33256D01*
G01X195584Y39256D02*
X194445Y40395D01*
G01X195584Y34550D02*
Y39256D01*
G01X194291Y33257D02*
X195584Y34550D01*
G01X196934Y39256D02*
X198073Y40395D01*
G01X196934Y34550D02*
Y39256D01*
G01X198228Y33256D02*
X196934Y34550D01*
G01X188725Y55275D02*
X189700Y54300D01*
G01X188725Y56425D02*
Y55275D01*
G01X189800Y57500D02*
X188725Y56425D01*
G01X189500Y57800D02*
X189800Y57500D01*
G01X189500Y60900D02*
Y57800D01*
G01X187375Y56325D02*
Y54810D01*
G01X188675Y66960D02*
X187172Y68463D01*
G01X188675Y65125D02*
Y66960D01*
G01X189500Y64300D02*
X188675Y65125D01*
G01X187325D02*
Y66400D01*
G01X189065Y75935D02*
Y73450D01*
G01X187095Y75895D02*
Y73450D01*
G01X196945D02*
Y76055D01*
G01X194975Y73450D02*
Y75975D01*
G01X188800Y76200D02*
X189065Y75935D01*
G01X188800Y78610D02*
Y76200D01*
G01X187450Y76250D02*
X187095Y75895D01*
G01X187450Y78050D02*
Y76250D01*
G01X196635Y79150D02*
X197845Y80360D01*
G01X196635Y76365D02*
Y79150D01*
G01X196945Y76055D02*
X196635Y76365D01*
G01X195285Y79150D02*
X194075Y80360D01*
G01X195285Y76285D02*
Y79150D01*
G01X194975Y75975D02*
X195285Y76285D01*
G01X201899Y134200D02*
X203200Y135501D01*
G01X188796Y129824D02*
X187146D01*
G01X189586Y129034D02*
X188796Y129824D01*
G01X191236Y129034D02*
X189586D01*
G01X192026Y129824D02*
X191236Y129034D01*
G01X195404Y129824D02*
X192026D01*
G01X202600Y122628D02*
X195404Y129824D01*
G01X195964Y131174D02*
X203950Y123188D01*
G01X194623Y151267D02*
Y149723D01*
G01X193150Y152740D02*
X194623Y151267D01*
G01X201800Y141200D02*
Y161200D01*
G01X203200Y139800D02*
X201800Y141200D01*
G01X193150Y155650D02*
Y152740D01*
G01X195050Y157550D02*
X193150Y155650D01*
G01X195050Y164350D02*
Y157550D01*
G01X198950Y168250D02*
X195050Y164350D01*
G01X195790Y152010D02*
X197140D01*
G01X194500Y153300D02*
X195790Y152010D01*
G01X194500Y155090D02*
Y153300D01*
G01X196400Y156990D02*
X194500Y155090D01*
G01X196400Y163790D02*
Y156990D01*
G01X200300Y167690D02*
X196400Y163790D01*
G01X188600Y152300D02*
Y173200D01*
G01X189950Y172640D02*
Y151740D01*
G01X201800Y161200D02*
X203550Y162950D01*
G01X198950Y172550D02*
Y168250D01*
G01X197550Y173950D02*
X198950Y172550D01*
G01X197550Y180040D02*
Y173950D01*
G01X193742Y183848D02*
X197550Y180040D01*
G01X200300Y173110D02*
Y167690D01*
G01X198900Y174510D02*
X200300Y173110D01*
G01X198900Y180600D02*
Y174510D01*
G01X194078Y185422D02*
X198900Y180600D01*
G01X189200Y173800D02*
Y176298D01*
G01X188600Y173200D02*
X189200Y173800D01*
G01X190550Y173240D02*
X189950Y172640D01*
G01X190550Y176858D02*
Y173240D01*
G01X187633Y179775D02*
X190550Y176858D01*
G01X187633Y181448D02*
Y179775D01*
G01X191607Y183848D02*
X193742D01*
G01X191607Y185422D02*
X194078D01*
G01X194409Y194871D02*
X191607D01*
G01X194521Y194983D02*
X194409Y194871D01*
G01X195783Y194983D02*
X194521D01*
G01X199150Y198350D02*
X195783Y194983D01*
G01X194408Y196446D02*
X191607D01*
G01X194521Y196333D02*
X194408Y196446D01*
G01X195223Y196333D02*
X194521D01*
G01X198590Y199700D02*
X195223Y196333D01*
G01X198316Y188672D02*
X199441Y187547D01*
G01X191707Y188672D02*
X198316D01*
G01X191607Y188572D02*
X191707Y188672D01*
G01X198467Y190022D02*
X199392Y190947D01*
G01X191732Y190022D02*
X198467D01*
G01X191607Y190147D02*
X191732Y190022D01*
G01X193797Y198021D02*
X198026Y202250D01*
G01X192350Y212050D02*
X219743D01*
G01X192910Y210700D02*
X219183D01*
G01X187633Y205423D02*
X192910Y210700D01*
G01X187633Y203570D02*
Y205423D01*
G01X204050Y198350D02*
X199150D01*
G01X204610Y199700D02*
X198590D01*
G01X198026Y202250D02*
X205700D01*
G01X191607Y198021D02*
X193797D01*
G01X197466Y203600D02*
X206260D01*
G01X193462Y199596D02*
X197466Y203600D01*
G01X191607Y199596D02*
X193462D01*
G01X188740Y215950D02*
X221360D01*
G01X189300Y214600D02*
X220800D01*
G01X202600Y116800D02*
Y122628D01*
G01X204450Y114950D02*
X202600Y116800D01*
G01X208080Y114950D02*
X204450D01*
G01X209259Y113771D02*
X208080Y114950D01*
G01X208129Y116300D02*
X209259Y117430D01*
G01X205010Y116300D02*
X208129D01*
G01X203950Y117360D02*
X205010Y116300D01*
G01X203950Y123188D02*
Y117360D01*
G01X203200Y135501D02*
Y139800D01*
G01X204550Y135030D02*
Y140360D01*
G01X205380Y134200D02*
X204550Y135030D01*
G01X203150Y141760D02*
Y160640D01*
G01X204550Y140360D02*
X203150Y141760D01*
G01X208000Y140250D02*
X206790Y139040D01*
G01X208000Y140900D02*
Y140250D01*
G01X205700Y143200D02*
X208000Y140900D01*
G01X205700Y159583D02*
Y143200D01*
G01X209350Y140225D02*
X210547Y139028D01*
G01X209350Y141460D02*
Y140225D01*
G01X207050Y143760D02*
X209350Y141460D01*
G01X207050Y159023D02*
Y143760D01*
G01X203550Y162950D02*
Y180392D01*
G01X204900Y162390D02*
Y179832D01*
G01X203150Y160640D02*
X204900Y162390D01*
G01X207450Y161333D02*
X205700Y159583D01*
G01X207450Y178775D02*
Y161333D01*
G01X208800Y160773D02*
X207050Y159023D01*
G01X208800Y178215D02*
Y160773D01*
G01X203550Y180392D02*
X209900Y186742D01*
G01X204900Y179832D02*
X211250Y186182D01*
G01X213800Y185125D02*
X207450Y178775D01*
G01X215150Y184565D02*
X208800Y178215D01*
G01X207650Y194750D02*
X204050Y198350D01*
G01X207650Y191423D02*
Y194750D01*
G01X209900Y189173D02*
X207650Y191423D01*
G01X209900Y186742D02*
Y189173D01*
G01X209000Y195310D02*
X204610Y199700D01*
G01X209000Y191983D02*
Y195310D01*
G01X211250Y189733D02*
X209000Y191983D01*
G01X211250Y186182D02*
Y189733D01*
G01X213800Y190790D02*
Y185125D01*
G01X211550Y193040D02*
X213800Y190790D01*
G01X211550Y196400D02*
Y193040D01*
G01X205700Y202250D02*
X211550Y196400D01*
G01X215150Y191350D02*
Y184565D01*
G01X212900Y193600D02*
X215150Y191350D01*
G01X212900Y196960D02*
Y193600D01*
G01X206260Y203600D02*
X212900Y196960D01*
G01X230860Y141850D02*
X233665D01*
G01X229687Y143023D02*
X230860Y141850D01*
G01X229687Y145610D02*
Y143023D01*
G01X230427Y146350D02*
X229687Y145610D01*
G01X230427Y165043D02*
Y146350D01*
G01X230300Y140500D02*
X233665D01*
G01X228337Y142463D02*
X230300Y140500D01*
G01X228337Y146170D02*
Y142463D01*
G01X229077Y146910D02*
X228337Y146170D01*
G01X229077Y164483D02*
Y146910D01*
G01X225577Y169893D02*
X230427Y165043D01*
G01X224227Y169333D02*
X229077Y164483D01*
G01X225577Y171833D02*
Y169893D01*
G01X220500Y176910D02*
X225577Y171833D01*
G01X220500Y182000D02*
Y176910D01*
G01X224000Y185500D02*
X220500Y182000D01*
G01X224227Y171273D02*
Y169333D01*
G01X219150Y176350D02*
X224227Y171273D01*
G01X219150Y182560D02*
Y176350D01*
G01X222650Y186060D02*
X219150Y182560D01*
G01X228100Y190900D02*
X235950Y183050D01*
G01X228100Y209210D02*
Y190900D01*
G01X226750Y190340D02*
X235390Y181700D01*
G01X226750Y208650D02*
Y190340D01*
G01X224000Y207793D02*
Y185500D01*
G01X222650Y207233D02*
Y186060D01*
G01X221360Y215950D02*
X228100Y209210D01*
G01X220800Y214600D02*
X226750Y208650D01*
G01X219743Y212050D02*
X224000Y207793D01*
G01X219183Y210700D02*
X222650Y207233D01*
G01X245472Y22892D02*
Y33257D01*
G01X241535Y22892D02*
Y33256D01*
G01X244229Y39201D02*
X245385Y40357D01*
G01X244229Y34500D02*
Y39201D01*
G01X245472Y33257D02*
X244229Y34500D01*
G01X242879Y39243D02*
X241765Y40357D01*
G01X242879Y34600D02*
Y39243D01*
G01X241535Y33256D02*
X242879Y34600D01*
G01X233665Y141850D02*
X234875Y143060D01*
G01X233665Y140500D02*
X234875Y139290D01*
G01X238800Y181700D02*
X239900Y180600D01*
G01X235390Y181700D02*
X238800D01*
G01X239176Y183050D02*
X240119Y183993D01*
G01X235950Y183050D02*
X239176D01*
G01X261220Y22892D02*
Y33257D01*
G01X257283Y22892D02*
Y33256D01*
G01X259927Y34550D02*
Y47192D01*
G01X261220Y33257D02*
X259927Y34550D01*
G01X258577D02*
Y47752D01*
G01X257283Y33256D02*
X258577Y34550D01*
G01X261175Y50875D02*
X262000Y51700D01*
G01X261175Y48440D02*
Y50875D01*
G01X259927Y47192D02*
X261175Y48440D01*
G01X259825Y50875D02*
X259000Y51700D01*
G01X259825Y49000D02*
Y50875D01*
G01X258577Y47752D02*
X259825Y49000D01*
G01X262000Y55300D02*
Y57800D01*
G01X259000Y55300D02*
Y57800D01*
G01X261933Y109267D02*
X262700Y108500D01*
G01X255600Y109267D02*
X261933D01*
G01X254601Y108268D02*
X255600Y109267D01*
G01X251758Y108268D02*
X254601D01*
G01X261817Y110617D02*
X262700Y111500D01*
G01X255400Y110617D02*
X261817D01*
G01X254600Y111417D02*
X255400Y110617D01*
G01X251758Y111417D02*
X254600D01*
G01X261025Y119375D02*
X257284Y123116D01*
G01X261875Y119375D02*
X261025D01*
G01X262700Y120200D02*
X261875Y119375D01*
G01X254900Y120866D02*
X251758D01*
G01X255800Y121766D02*
X254900Y120866D01*
G01X260465Y118025D02*
X256724Y121766D01*
G01X261875Y118025D02*
X260465D01*
G01X262700Y117200D02*
X261875Y118025D01*
G01X254900Y124016D02*
X251758D01*
G01X255800Y123116D02*
X254900Y124016D01*
G01X257284Y123116D02*
X255800D01*
G01X256724Y121766D02*
X255800D01*
G01X273031Y22892D02*
Y33256D01*
G01X276968Y22892D02*
Y33257D01*
G01X272045Y41180D02*
Y45745D01*
G01X274325Y38900D02*
X272045Y41180D01*
G01X274325Y34550D02*
Y38900D01*
G01X273031Y33256D02*
X274325Y34550D01*
G01X273395Y41740D02*
Y46305D01*
G01X275675Y39460D02*
X273395Y41740D01*
G01X275675Y34550D02*
Y39460D01*
G01X276968Y33257D02*
X275675Y34550D01*
G01X268000Y55300D02*
Y57500D01*
G01X269050Y50650D02*
X268000Y51700D01*
G01X269050Y48740D02*
Y50650D01*
G01X272045Y45745D02*
X269050Y48740D01*
G01X270400Y51100D02*
X271000Y51700D01*
G01X270400Y49300D02*
Y51100D01*
G01X273395Y46305D02*
X270400Y49300D01*
G01X271000Y55300D02*
Y57500D01*
G01X271202Y109350D02*
X272200Y108352D01*
G01X267150Y109350D02*
X271202D01*
G01X266300Y108500D02*
X267150Y109350D01*
G01X271054Y110700D02*
X272185Y111831D01*
G01X267100Y110700D02*
X271054D01*
G01X266300Y111500D02*
X267100Y110700D01*
G01X267125Y119375D02*
X266300Y120200D01*
G01X271235Y119375D02*
X267125D01*
G01X276010Y114600D02*
X271235Y119375D01*
G01X281933Y114600D02*
X276010D01*
G01X267125Y118025D02*
X266300Y117200D01*
G01X270675Y118025D02*
X267125D01*
G01X275450Y113250D02*
X270675Y118025D01*
G01X281373Y113250D02*
X275450D01*
G01X288779Y22892D02*
Y33257D01*
G01X292716Y22892D02*
Y33256D01*
G01X290072Y34550D02*
Y45018D01*
G01X288779Y33257D02*
X290072Y34550D01*
G01X291422D02*
Y45578D01*
G01X292716Y33256D02*
X291422Y34550D01*
G01X287000Y57700D02*
X286800Y57900D01*
G01X287000Y55300D02*
Y57700D01*
G01X287825Y50875D02*
X287000Y51700D01*
G01X287825Y47265D02*
Y50875D01*
G01X290072Y45018D02*
X287825Y47265D01*
G01X289175Y50875D02*
X290000Y51700D01*
G01X289175Y47825D02*
Y50875D01*
G01X291422Y45578D02*
X289175Y47825D01*
G01X290000Y57700D02*
X290200Y57900D01*
G01X290000Y55300D02*
Y57700D01*
G01X288632Y107901D02*
X281933Y114600D01*
G01X296186Y107901D02*
X288632D01*
G01X288072Y106551D02*
X281373Y113250D01*
G01X296746Y106551D02*
X288072D01*
G01X304527Y22892D02*
Y33257D01*
G01X308464Y22892D02*
Y33256D01*
G01X305820Y34550D02*
Y50380D01*
G01X304527Y33257D02*
X305820Y34550D01*
G01X307170D02*
Y50370D01*
G01X308464Y33256D02*
X307170Y34550D01*
G01X305000Y57200D02*
X304800Y57400D01*
G01X305000Y54800D02*
Y57200D01*
G01X305820Y50380D02*
X305000Y51200D01*
G01X307170Y50370D02*
X308000Y51200D01*
G01Y57200D02*
X308200Y57400D01*
G01X308000Y54800D02*
Y57200D01*
G01X302725Y114440D02*
X296186Y107901D01*
G01X302725Y115900D02*
Y114440D01*
G01X304075Y113880D02*
X296746Y106551D01*
G01X304075Y115900D02*
Y113880D01*
G01X324212Y22892D02*
Y33257D01*
G01X320275Y22892D02*
Y33256D01*
G01X322919Y40081D02*
X318150Y44850D01*
G01X322919Y34550D02*
Y40081D01*
G01X324212Y33257D02*
X322919Y34550D01*
G01X321569Y39521D02*
X316800Y44290D01*
G01X321569Y34550D02*
Y39521D01*
G01X320275Y33256D02*
X321569Y34550D01*
G01X319000Y57200D02*
X319200Y57400D01*
G01X319000Y54800D02*
Y57200D01*
G01X318150Y50350D02*
X319000Y51200D01*
G01X318150Y44850D02*
Y50350D01*
G01X316800Y50400D02*
X316000Y51200D01*
G01X316800Y44290D02*
Y50400D01*
G01X316000Y57200D02*
X315800Y57400D01*
G01X316000Y54800D02*
Y57200D01*
G01X325100Y53800D02*
X324000Y54900D01*
G01X325100Y52100D02*
Y53800D01*
G01X326850Y50350D02*
X325100Y52100D01*
G01X326450Y53950D02*
X327400Y54900D01*
G01X326450Y52660D02*
Y53950D01*
G01X327410Y51700D02*
X326450Y52660D01*
G01X346710Y51700D02*
X327410D01*
G01X346150Y50350D02*
X326850D01*
G01X355709Y22892D02*
Y33256D01*
G01X351772Y22892D02*
Y33257D01*
G01X354415Y34550D02*
Y43995D01*
G01X355709Y33256D02*
X354415Y34550D01*
G01X353065Y43435D02*
X346150Y50350D01*
G01X353065Y34550D02*
Y43435D01*
G01X351772Y33257D02*
X353065Y34550D01*
G01X354415Y43995D02*
X346710Y51700D01*
G54D15*
G01X609253Y252106D02*
X609937D01*
G01X608640Y251493D02*
X609253Y252106D01*
G01X608640Y250027D02*
Y251493D01*
G01X609252Y249415D02*
X608640Y250027D01*
G01X609252Y246456D02*
Y249415D01*
G01X607190Y252590D02*
X609500Y254900D01*
G01X607190Y249800D02*
Y252590D01*
G01X606890Y249500D02*
X607190Y249800D01*
G01X606890Y246456D02*
Y249500D01*
G01X607771Y272771D02*
X605100Y270100D01*
G01X607771Y275400D02*
Y272771D01*
G01X605367Y272967D02*
X605065D01*
G01X606321Y273921D02*
X605367Y272967D01*
G01X606321Y275179D02*
Y273921D01*
G01X605709Y275791D02*
X606321Y275179D01*
G01X608071Y275700D02*
X607771Y275400D01*
G01X608071Y278740D02*
Y275700D01*
G01X605709Y278740D02*
Y275791D01*
G01X646166Y13256D02*
X648400Y15490D01*
G01X646166Y10207D02*
Y13256D01*
G01X645866Y9907D02*
X646166Y10207D01*
G01X645866Y6656D02*
Y9907D01*
G01X648609Y12707D02*
X648800D01*
G01X647616Y11714D02*
X648609Y12707D01*
G01X647616Y10228D02*
Y11714D01*
G01X648228Y9616D02*
X647616Y10228D01*
G01X648228Y6656D02*
Y9616D01*
G01X644685Y34275D02*
X643700Y33290D01*
G01X644685Y38940D02*
Y34275D01*
G01X645475Y31682D02*
X644100Y30307D01*
G01X645475Y33014D02*
Y31682D01*
G01X646135Y33674D02*
X645475Y33014D01*
G01X646135Y35269D02*
Y33674D01*
G01X647047Y36181D02*
X646135Y35269D01*
G01X647047Y38940D02*
Y36181D01*
M02*
